(kicad_pcb
	(version 20260206)
	(generator "pcbnew")
	(generator_version "10.0")
	(general
		(thickness 1.6)
		(legacy_teardrops no)
	)
	(paper "A4")
	(title_block
		(title "fcb — 12433-1M.1206WZS1330.brd")
		(comment 1 "Open Vault / Knox (Wiwynn) / footprints 290-294 of 495")
	)
	(layers
		(0 "F.Cu" signal "TOP")
		(4 "In1.Cu" signal "L2GND")
		(6 "In2.Cu" signal "L3VCC")
		(2 "B.Cu" signal "BOTTOM")
		(9 "F.Adhes" user "F.Adhesive")
		(11 "B.Adhes" user "B.Adhesive")
		(13 "F.Paste" user "Package Geometry/Pastemask Top")
		(15 "B.Paste" user "Package Geometry/Pastemask Bottom")
		(5 "F.SilkS" user "Ref Des/Silkscreen Top")
		(7 "B.SilkS" user "Ref Des/Silkscreen Bottom")
		(1 "F.Mask" user "Board Geometry/Soldermask Top")
		(3 "B.Mask" user "Board Geometry/Soldermask Bottom")
		(17 "Dwgs.User" user "User.Drawings")
		(19 "Cmts.User" user "User.Comments")
		(21 "Eco1.User" user "User.Eco1")
		(23 "Eco2.User" user "User.Eco2")
		(25 "Edge.Cuts" user "Board Geometry/Outline")
		(27 "Margin" user)
		(31 "F.CrtYd" user "Package Geometry/Place Bound Top")
		(29 "B.CrtYd" user "Package Geometry/Place Bound Bottom")
		(35 "F.Fab" user "Ref Des/Assembly Top")
		(33 "B.Fab" user "Ref Des/Assembly Bottom")
	)
	(footprint ""
		(layer "F.Cu")
		(at 33.655 -410.591)
		(property "Reference" "PR31"
			(at 0 0 0)
			(layer "F.SilkS")
			(hide yes)
			(effects
				(font
					(size 1.27 1.27)
				)
			)
		)
		(property "Value" "D0005RL1632F-GP-U"
			(at 3.2258 1.2954 0)
			(unlocked yes)
			(layer "F.Fab")
			(hide yes)
			(effects
				(font
					(size 1.016 1.016)
					(thickness 0.1524)
				)
			)
		)
		(property "Device Type" "RL3115-4PH45"
			(at 3.2258 -0.2286 0)
			(unlocked yes)
			(layer "F.Fab")
			(hide yes)
			(effects
				(font
					(size 1.016 1.016)
					(thickness 0.1524)
				)
			)
		)
		(duplicate_pad_numbers_are_jumpers no)
		(fp_line
			(start -2.0574 -1.7653)
			(end -2.0574 -0.4064)
			(stroke
				(width 0.3302)
				(type default)
			)
			(layer "F.SilkS")
		)
		(fp_line
			(start -1.9685 -1.651)
			(end 1.9685 -1.651)
			(stroke
				(width 0.1524)
				(type default)
			)
			(layer "F.SilkS")
		)
		(fp_line
			(start -1.9685 1.651)
			(end -1.9685 -1.651)
			(stroke
				(width 0.1524)
				(type default)
			)
			(layer "F.SilkS")
		)
		(fp_line
			(start -0.5334 -1.7653)
			(end -2.0574 -1.7653)
			(stroke
				(width 0.3302)
				(type default)
			)
			(layer "F.SilkS")
		)
		(fp_line
			(start 1.9685 -1.651)
			(end 1.9685 1.651)
			(stroke
				(width 0.1524)
				(type default)
			)
			(layer "F.SilkS")
		)
		(fp_line
			(start 1.9685 1.651)
			(end -1.9685 1.651)
			(stroke
				(width 0.1524)
				(type default)
			)
			(layer "F.SilkS")
		)
		(fp_poly
			(pts
				(xy -0.561594 -1.726946) (xy -0.053594 -2.234946) (xy -1.069594 -2.234946)
			)
			(stroke
				(width 0)
				(type default)
			)
			(fill yes)
			(layer "F.SilkS")
		)
		(fp_rect
			(start -1.524 0.7493)
			(end 1.524 -0.7493)
			(stroke
				(width 0)
				(type default)
			)
			(fill no)
			(layer "F.CrtYd")
		)
		(fp_poly
			(pts
				(xy -2.2225 1.905) (xy -2.2225 -1.905) (xy 2.2225 -1.905) (xy 2.2225 -0.7493) (xy -1.524 -0.7493)
				(xy -1.524 0.7493) (xy 1.524 0.7493) (xy 1.524 -0.7366) (xy 2.2225 -0.7366) (xy 2.2225 1.905)
			)
			(stroke
				(width 0)
				(type default)
			)
			(fill no)
			(layer "F.CrtYd")
		)
		(pad "1" smd rect
			(at -0.5715 -0.813562)
			(size 2.286 1.143)
			(layers "F.Cu" "F.Mask" "F.Paste")
			(net "P12V_AUX")
		)
		(pad "2" smd rect
			(at -0.5715 0.813562)
			(size 2.286 1.143)
			(layers "F.Cu" "F.Mask" "F.Paste")
			(net "P12V_SENSE_TRACE")
		)
		(pad "3" smd rect
			(at 1.334008 -0.813562)
			(size 0.762 1.143)
			(layers "F.Cu" "F.Mask" "F.Paste")
			(net "SENSE+_R3")
		)
		(pad "4" smd rect
			(at 1.334008 0.813562)
			(size 0.762 1.143)
			(layers "F.Cu" "F.Mask" "F.Paste")
			(net "SENSE-_R3")
		)
		(zone
			(layer "F.Cu")
			(hatch none 0.5)
			(connect_pads
				(clearance 0)
			)
			(min_thickness 0.25)
			(keepout
				(tracks allowed)
				(vias not_allowed)
				(pads allowed)
				(copperpour not_allowed)
				(footprints allowed)
			)
			(placement
				(enabled no)
				(sheetname "")
			)
			(fill
				(thermal_gap 0.5)
				(thermal_bridge_width 0.5)
				(island_removal_mode 0)
			)
			(polygon
				(pts
					(xy 34.2265 -410.833062) (xy 34.608008 -410.833062) (xy 34.608008 -411.3403) (xy 34.2265 -411.3403)
				)
			)
		)
		(zone
			(layer "F.Cu")
			(hatch none 0.5)
			(connect_pads
				(clearance 0)
			)
			(min_thickness 0.25)
			(keepout
				(tracks not_allowed)
				(vias allowed)
				(pads allowed)
				(copperpour not_allowed)
				(footprints allowed)
			)
			(placement
				(enabled no)
				(sheetname "")
			)
			(fill
				(thermal_gap 0.5)
				(thermal_bridge_width 0.5)
				(island_removal_mode 0)
			)
			(polygon
				(pts
					(xy 34.2265 -410.833062) (xy 34.608008 -410.833062) (xy 34.608008 -411.3403) (xy 34.2265 -411.3403)
				)
			)
		)
		(zone
			(layer "F.Cu")
			(hatch none 0.5)
			(connect_pads
				(clearance 0)
			)
			(min_thickness 0.25)
			(keepout
				(tracks not_allowed)
				(vias allowed)
				(pads allowed)
				(copperpour not_allowed)
				(footprints allowed)
			)
			(placement
				(enabled no)
				(sheetname "")
			)
			(fill
				(thermal_gap 0.5)
				(thermal_bridge_width 0.5)
				(island_removal_mode 0)
			)
			(polygon
				(pts
					(xy 34.2265 -409.8417) (xy 34.608008 -409.8417) (xy 34.608008 -410.348938) (xy 34.2265 -410.348938)
				)
			)
		)
		(zone
			(layer "F.Cu")
			(hatch none 0.5)
			(connect_pads
				(clearance 0)
			)
			(min_thickness 0.25)
			(keepout
				(tracks allowed)
				(vias not_allowed)
				(pads allowed)
				(copperpour not_allowed)
				(footprints allowed)
			)
			(placement
				(enabled no)
				(sheetname "")
			)
			(fill
				(thermal_gap 0.5)
				(thermal_bridge_width 0.5)
				(island_removal_mode 0)
			)
			(polygon
				(pts
					(xy 34.2265 -409.8417) (xy 34.608008 -409.8417) (xy 34.608008 -410.348938) (xy 34.2265 -410.348938)
				)
			)
		)
	)
	(footprint ""
		(layer "F.Cu")
		(at 24.257 -371.475 180)
		(property "Reference" "PR36"
			(at 0 0 180)
			(layer "F.SilkS")
			(hide yes)
			(effects
				(font
					(size 1.27 1.27)
				)
			)
		)
		(property "Value" "4K02R2F-GP"
			(at 0.064008 -3.993896 180)
			(unlocked yes)
			(layer "F.Fab")
			(hide yes)
			(effects
				(font
					(size 1.016 1.016)
					(thickness 0.1524)
				)
			)
		)
		(property "Device Type" "R402H16"
			(at 0.064008 -5.517896 180)
			(unlocked yes)
			(layer "F.Fab")
			(hide yes)
			(effects
				(font
					(size 1.016 1.016)
					(thickness 0.1524)
				)
			)
		)
		(duplicate_pad_numbers_are_jumpers no)
		(fp_line
			(start 0.508 -0.9398)
			(end -0.508 -0.9398)
			(stroke
				(width 0.1524)
				(type default)
			)
			(layer "F.SilkS")
		)
		(fp_line
			(start -0.508 -0.9398)
			(end -0.508 0.9398)
			(stroke
				(width 0.1524)
				(type default)
			)
			(layer "F.SilkS")
		)
		(fp_rect
			(start -0.508 0.9398)
			(end 0.508 -0.9398)
			(stroke
				(width 0)
				(type default)
			)
			(fill no)
			(layer "F.CrtYd")
		)
		(fp_rect
			(start -0.508 0.9398)
			(end 0.508 -0.9398)
			(stroke
				(width 0)
				(type default)
			)
			(fill no)
			(layer "F.Fab")
		)
		(pad "1" smd custom
			(at 0 -0.4445 180)
			(size 0.1397 0.1397)
			(layers "F.Cu" "F.Mask" "F.Paste")
			(net "ADM1276_OV")
			(options
				(clearance outline)
				(anchor circle)
			)
			(primitives
				(gr_poly
					(pts
						(arc
							(start -0.1778 -0.2794)
							(mid -0.249642 -0.249642)
							(end -0.2794 -0.1778)
						)
						(arc
							(start -0.2794 0.1778)
							(mid -0.249642 0.249642)
							(end -0.1778 0.2794)
						)
						(arc
							(start 0.1778 0.2794)
							(mid 0.249642 0.249642)
							(end 0.2794 0.1778)
						)
						(arc
							(start 0.2794 -0.1778)
							(mid 0.249642 -0.249642)
							(end 0.1778 -0.2794)
						)
					)
					(width 0)
					(fill yes)
				)
			)
		)
		(pad "2" smd custom
			(at 0 0.4445 180)
			(size 0.1397 0.1397)
			(layers "F.Cu" "F.Mask" "F.Paste")
			(net "GND")
			(options
				(clearance outline)
				(anchor circle)
			)
			(primitives
				(gr_poly
					(pts
						(arc
							(start -0.1778 -0.2794)
							(mid -0.249642 -0.249642)
							(end -0.2794 -0.1778)
						)
						(arc
							(start -0.2794 0.1778)
							(mid -0.249642 0.249642)
							(end -0.1778 0.2794)
						)
						(arc
							(start 0.1778 0.2794)
							(mid 0.249642 0.249642)
							(end 0.2794 0.1778)
						)
						(arc
							(start 0.2794 -0.1778)
							(mid 0.249642 -0.249642)
							(end 0.1778 -0.2794)
						)
					)
					(width 0)
					(fill yes)
				)
			)
		)
	)
	(footprint ""
		(layer "F.Cu")
		(at 34.544 -400.177)
		(property "Reference" "PQ2"
			(at 0 0 0)
			(layer "F.SilkS")
			(hide yes)
			(effects
				(font
					(size 1.27 1.27)
				)
			)
		)
		(property "Value" "PH0925CL-GP"
			(at -4.2799 -0.4572 0)
			(unlocked yes)
			(layer "F.Fab")
			(hide yes)
			(effects
				(font
					(size 1.016 1.016)
					(thickness 0.1524)
				)
			)
		)
		(property "Device Type" "LFPAK-5PH48-U"
			(at -4.2799 -1.9812 0)
			(unlocked yes)
			(layer "F.Fab")
			(hide yes)
			(effects
				(font
					(size 1.016 1.016)
					(thickness 0.1524)
				)
			)
		)
		(duplicate_pad_numbers_are_jumpers no)
		(fp_line
			(start -2.7559 -6.5532)
			(end -2.7559 1.0668)
			(stroke
				(width 0.1524)
				(type default)
			)
			(layer "F.SilkS")
		)
		(fp_line
			(start -2.7559 1.0668)
			(end 2.7559 1.0668)
			(stroke
				(width 0.1524)
				(type default)
			)
			(layer "F.SilkS")
		)
		(fp_line
			(start -1.7272 1.1684)
			(end -2.1082 1.1684)
			(stroke
				(width 0.3302)
				(type default)
			)
			(layer "F.SilkS")
		)
		(fp_line
			(start 2.7559 -6.5532)
			(end -2.7559 -6.5532)
			(stroke
				(width 0.1524)
				(type default)
			)
			(layer "F.SilkS")
		)
		(fp_line
			(start 2.7559 1.0668)
			(end 2.7559 -6.5532)
			(stroke
				(width 0.1524)
				(type default)
			)
			(layer "F.SilkS")
		)
		(fp_poly
			(pts
				(xy -2.3368 1.5748) (xy -1.905 1.143) (xy -1.4732 1.5748)
			)
			(stroke
				(width 0)
				(type default)
			)
			(fill yes)
			(layer "F.SilkS")
		)
		(fp_poly
			(pts
				(xy -2.5019 -4.02971) (xy -0.3302 -4.02971) (xy -0.3302 -6.30301) (xy -2.5019 -6.30301)
			)
			(stroke
				(width 0)
				(type default)
			)
			(fill yes)
			(layer "F.Paste")
		)
		(fp_poly
			(pts
				(xy -2.5019 -1.09601) (xy -0.3302 -1.09601) (xy -0.3302 -3.36931) (xy -2.5019 -3.36931)
			)
			(stroke
				(width 0)
				(type default)
			)
			(fill yes)
			(layer "F.Paste")
		)
		(fp_poly
			(pts
				(xy 0.3302 -4.02971) (xy 2.5019 -4.02971) (xy 2.5019 -6.30301) (xy 0.3302 -6.30301)
			)
			(stroke
				(width 0)
				(type default)
			)
			(fill yes)
			(layer "F.Paste")
		)
		(fp_poly
			(pts
				(xy 0.3302 -1.09601) (xy 2.5019 -1.09601) (xy 2.5019 -3.36931) (xy 0.3302 -3.36931)
			)
			(stroke
				(width 0)
				(type default)
			)
			(fill yes)
			(layer "F.Paste")
		)
		(fp_rect
			(start -2.4511 0.3048)
			(end 2.4511 -5.6896)
			(stroke
				(width 0)
				(type default)
			)
			(fill no)
			(layer "F.CrtYd")
		)
		(fp_poly
			(pts
				(xy -3.0099 1.3208) (xy -3.0099 -6.8072) (xy 3.0099 -6.8072) (xy 3.0099 -1.016) (xy 2.4511 -1.016)
				(xy 2.4511 -5.6896) (xy -2.4511 -5.6896) (xy -2.4511 0.3048) (xy 2.4511 0.3048) (xy 2.4511 -1.0033)
				(xy 3.0099 -1.0033) (xy 3.0099 1.3208)
			)
			(stroke
				(width 0)
				(type default)
			)
			(fill no)
			(layer "F.CrtYd")
		)
		(fp_rect
			(start -3.0099 1.3208)
			(end 3.0099 -6.8072)
			(stroke
				(width 0)
				(type default)
			)
			(fill no)
			(layer "F.Fab")
		)
		(pad "1" smd rect
			(at -1.905 0)
			(size 0.762 1.6256)
			(layers "F.Cu" "F.Mask" "F.Paste")
			(net "P12V")
		)
		(pad "2" smd rect
			(at -0.635 0)
			(size 0.762 1.6256)
			(layers "F.Cu" "F.Mask" "F.Paste")
			(net "P12V")
		)
		(pad "3" smd rect
			(at 0.635 0)
			(size 0.762 1.6256)
			(layers "F.Cu" "F.Mask" "F.Paste")
			(net "P12V")
		)
		(pad "4" smd rect
			(at 1.905 0)
			(size 0.762 1.6256)
			(layers "F.Cu" "F.Mask" "F.Paste")
			(net "ADM1276_GATE_DRV2")
		)
		(pad "5" smd rect
			(at 0 -3.69951)
			(size 5.0038 5.207)
			(layers "F.Cu" "F.Mask" "F.Paste")
			(net "P12V_SENSE_TRACE")
		)
	)
	(footprint ""
		(layer "F.Cu")
		(at 34.544 -240.3094 180)
		(property "Reference" "R55"
			(at 0 0 180)
			(layer "F.SilkS")
			(hide yes)
			(effects
				(font
					(size 1.27 1.27)
				)
			)
		)
		(property "Value" "4K7R2J-2-GP"
			(at 0.064008 -3.993896 180)
			(unlocked yes)
			(layer "F.Fab")
			(hide yes)
			(effects
				(font
					(size 1.016 1.016)
					(thickness 0.1524)
				)
			)
		)
		(property "Device Type" "R402H16"
			(at 0.064008 -5.517896 180)
			(unlocked yes)
			(layer "F.Fab")
			(hide yes)
			(effects
				(font
					(size 1.016 1.016)
					(thickness 0.1524)
				)
			)
		)
		(duplicate_pad_numbers_are_jumpers no)
		(fp_line
			(start 0.508 -0.9398)
			(end -0.508 -0.9398)
			(stroke
				(width 0.1524)
				(type default)
			)
			(layer "F.SilkS")
		)
		(fp_line
			(start -0.508 -0.9398)
			(end -0.508 0.9398)
			(stroke
				(width 0.1524)
				(type default)
			)
			(layer "F.SilkS")
		)
		(fp_rect
			(start -0.508 0.9398)
			(end 0.508 -0.9398)
			(stroke
				(width 0)
				(type default)
			)
			(fill no)
			(layer "F.CrtYd")
		)
		(fp_rect
			(start -0.508 0.9398)
			(end 0.508 -0.9398)
			(stroke
				(width 0)
				(type default)
			)
			(fill no)
			(layer "F.Fab")
		)
		(pad "1" smd custom
			(at 0 -0.4445 180)
			(size 0.1397 0.1397)
			(layers "F.Cu" "F.Mask" "F.Paste")
			(net "GND")
			(options
				(clearance outline)
				(anchor circle)
			)
			(primitives
				(gr_poly
					(pts
						(arc
							(start -0.1778 -0.2794)
							(mid -0.249642 -0.249642)
							(end -0.2794 -0.1778)
						)
						(arc
							(start -0.2794 0.1778)
							(mid -0.249642 0.249642)
							(end -0.1778 0.2794)
						)
						(arc
							(start 0.1778 0.2794)
							(mid 0.249642 0.249642)
							(end 0.2794 0.1778)
						)
						(arc
							(start 0.2794 -0.1778)
							(mid 0.249642 -0.249642)
							(end 0.1778 -0.2794)
						)
					)
					(width 0)
					(fill yes)
				)
			)
		)
		(pad "2" smd custom
			(at 0 0.4445 180)
			(size 0.1397 0.1397)
			(layers "F.Cu" "F.Mask" "F.Paste")
			(net "LED_DRV_A1")
			(options
				(clearance outline)
				(anchor circle)
			)
			(primitives
				(gr_poly
					(pts
						(arc
							(start -0.1778 -0.2794)
							(mid -0.249642 -0.249642)
							(end -0.2794 -0.1778)
						)
						(arc
							(start -0.2794 0.1778)
							(mid -0.249642 0.249642)
							(end -0.1778 0.2794)
						)
						(arc
							(start 0.1778 0.2794)
							(mid 0.249642 0.249642)
							(end 0.2794 0.1778)
						)
						(arc
							(start 0.2794 -0.1778)
							(mid 0.249642 -0.249642)
							(end 0.1778 -0.2794)
						)
					)
					(width 0)
					(fill yes)
				)
			)
		)
	)
	(footprint ""
		(layer "F.Cu")
		(at 8.9662 -101.0412 -90)
		(property "Reference" "TC1"
			(at 0 0 270)
			(layer "F.SilkS")
			(hide yes)
			(effects
				(font
					(size 1.27 1.27)
				)
			)
		)
		(property "Value" "ST68U16VDM-1-GP"
			(at 0 -9.6012 270)
			(unlocked yes)
			(layer "F.Fab")
			(hide yes)
			(effects
				(font
					(size 1.016 1.016)
					(thickness 0.1524)
				)
			)
		)
		(property "Device Type" "CT7343H79"
			(at 0 -11.1252 270)
			(unlocked yes)
			(layer "F.Fab")
			(hide yes)
			(effects
				(font
					(size 1.016 1.016)
					(thickness 0.1524)
				)
			)
		)
		(duplicate_pad_numbers_are_jumpers no)
		(fp_line
			(start -2.286 4.8768)
			(end -2.286 2.032)
			(stroke
				(width 0.1524)
				(type default)
			)
			(layer "F.SilkS")
		)
		(fp_line
			(start 2.286 4.8768)
			(end -2.286 4.8768)
			(stroke
				(width 0.1524)
				(type default)
			)
			(layer "F.SilkS")
		)
		(fp_line
			(start 2.286 2.032)
			(end 2.286 4.8768)
			(stroke
				(width 0.1524)
				(type default)
			)
			(layer "F.SilkS")
		)
		(fp_line
			(start 2.286 -2.032)
			(end 2.286 -4.8768)
			(stroke
				(width 0.1524)
				(type default)
			)
			(layer "F.SilkS")
		)
		(fp_line
			(start 2.1082 -4.699)
			(end -2.1082 -4.699)
			(stroke
				(width 0.508)
				(type default)
			)
			(layer "F.SilkS")
		)
		(fp_line
			(start -2.286 -4.8768)
			(end -2.286 -2.032)
			(stroke
				(width 0.1524)
				(type default)
			)
			(layer "F.SilkS")
		)
		(fp_line
			(start 2.286 -4.8768)
			(end -2.286 -4.8768)
			(stroke
				(width 0.1524)
				(type default)
			)
			(layer "F.SilkS")
		)
		(fp_rect
			(start -2.1463 3.6449)
			(end 2.1463 -3.6449)
			(stroke
				(width 0)
				(type default)
			)
			(fill no)
			(layer "F.CrtYd")
		)
		(fp_poly
			(pts
				(xy -2.54 4.953) (xy -2.54 4.2926) (xy -3.81 4.2926) (xy -3.81 -4.2926) (xy -2.54 -4.2926) (xy -2.54 -4.953)
				(xy 2.54 -4.953) (xy 2.54 -4.2926) (xy 3.81 -4.2926) (xy 3.81 -1.6256) (xy 2.1463 -1.6256) (xy 2.1463 -3.6449)
				(xy -2.1463 -3.6449) (xy -2.1463 3.6449) (xy 2.1463 3.6449) (xy 2.1463 -1.6129) (xy 3.81 -1.6129)
				(xy 3.81 4.2926) (xy 2.54 4.2926) (xy 2.54 4.953)
			)
			(stroke
				(width 0)
				(type default)
			)
			(fill no)
			(layer "F.CrtYd")
		)
		(fp_rect
			(start -2.54 4.953)
			(end 2.54 -4.953)
			(stroke
				(width 0)
				(type default)
			)
			(fill no)
			(layer "F.Fab")
		)
		(fp_rect
			(start -3.81 4.2926)
			(end -2.54 -4.2926)
			(stroke
				(width 0)
				(type default)
			)
			(fill no)
			(layer "F.Fab")
		)
		(fp_rect
			(start 2.54 4.2926)
			(end 3.81 -4.2926)
			(stroke
				(width 0)
				(type default)
			)
			(fill no)
			(layer "F.Fab")
		)
		(pad "1" smd rect
			(at 0 -3.1496 270)
			(size 2.413 2.286)
			(layers "F.Cu" "F.Mask" "F.Paste")
			(net "P12VU")
		)
		(pad "2" smd rect
			(at 0 3.1496 270)
			(size 2.413 2.286)
			(layers "F.Cu" "F.Mask" "F.Paste")
			(net "GND")
		)
		(zone
			(layer "F.Cu")
			(hatch none 0.5)
			(connect_pads
				(clearance 0)
			)
			(min_thickness 0.25)
			(keepout
				(tracks allowed)
				(vias not_allowed)
				(pads allowed)
				(copperpour not_allowed)
				(footprints allowed)
			)
			(placement
				(enabled no)
				(sheetname "")
			)
			(fill
				(thermal_gap 0.5)
				(thermal_bridge_width 0.5)
				(island_removal_mode 0)
			)
			(polygon
				(pts
					(xy 4.3688 -102.5525) (xy 4.3688 -99.5299) (xy 7.2644 -99.5299) (xy 7.5946 -99.5299) (xy 7.5946 -102.5525)
					(xy 7.2644 -102.5525)
				)
			)
		)
		(zone
			(layer "F.Cu")
			(hatch none 0.5)
			(connect_pads
				(clearance 0)
			)
			(min_thickness 0.25)
			(keepout
				(tracks allowed)
				(vias not_allowed)
				(pads allowed)
				(copperpour not_allowed)
				(footprints allowed)
			)
			(placement
				(enabled no)
				(sheetname "")
			)
			(fill
				(thermal_gap 0.5)
				(thermal_bridge_width 0.5)
				(island_removal_mode 0)
			)
			(polygon
				(pts
					(xy 10.6553 -99.5299) (xy 13.5636 -99.5299) (xy 13.5636 -102.5525) (xy 10.668 -102.5525) (xy 10.3378 -102.5525)
					(xy 10.3378 -99.5299)
				)
			)
		)
	)
)
